# TIMECARD (Time Appliance Project (Time Card)) — schematic netlist excerpt (pin names and nets, part order shuffled) for the footprints in the layout excerpt that follows; sources: Cadence DE-HDL packaged netlist, KiCad conversion of R4006-B0001-02_R01.brd

R197  RESISTOR  100OHM 1%  pkg SMC_0402R_H016  page 10 : \1\ = MHZ125CLKP_CLKIN ; \2\ = MHZ125CLKN_CLKIN
R146  RESISTOR  10KOHM 1%  pkg SMC_0402R_H016  page 16 : \1\ = XP3R3V_FPGA ; \2\ = PCA9546_RST_N

(kicad_pcb
	(version 20260206)
	(generator "pcbnew")
	(generator_version "10.0")
	(general
		(thickness 1.6)
		(legacy_teardrops no)
	)
	(paper "A4")
	(title_block
		(title "timecard-production-celestica-r4006 — R4006-B0001-02_R01.brd")
		(comment 1 "Time Appliance Project (Time Card) / footprints 825-826 of 1113")
	)
	(layers
		(0 "F.Cu" signal "TOP")
		(4 "In1.Cu" signal "L02_GND1")
		(6 "In2.Cu" signal "L03_SIG1")
		(8 "In3.Cu" signal "L04_GND2")
		(10 "In4.Cu" signal "L05_VCC1")
		(12 "In5.Cu" signal "L06_VCC2")
		(14 "In6.Cu" signal "L07_GND3")
		(16 "In7.Cu" signal "L08_SIG2")
		(18 "In8.Cu" signal "L09_GND4")
		(2 "B.Cu" signal "BOTTOM")
		(9 "F.Adhes" user "F.Adhesive")
		(11 "B.Adhes" user "B.Adhesive")
		(13 "F.Paste" user "Package Geometry/Pastemask Top")
		(15 "B.Paste" user "Package Geometry/Pastemask Bottom")
		(5 "F.SilkS" user "Ref Des/Silkscreen Top")
		(7 "B.SilkS" user "Ref Des/Silkscreen Bottom")
		(1 "F.Mask" user "Board Geometry/Soldermask Top")
		(3 "B.Mask" user "Board Geometry/Soldermask Bottom")
		(17 "Dwgs.User" user "User.Drawings")
		(19 "Cmts.User" user "User.Comments")
		(21 "Eco1.User" user "User.Eco1")
		(23 "Eco2.User" user "User.Eco2")
		(25 "Edge.Cuts" user "Board Geometry/Outline")
		(27 "Margin" user)
		(31 "F.CrtYd" user "Package Geometry/Place Bound Top")
		(29 "B.CrtYd" user "Package Geometry/Place Bound Bottom")
		(35 "F.Fab" user "Ref Des/Assembly Top")
		(33 "B.Fab" user "Ref Des/Assembly Bottom")
	)
	(footprint ""
		(layer "B.Cu")
		(at 103.347012 -37.82314)
		(property "Reference" "R197"
			(at -41.879012 1.40589 0)
			(unlocked yes)
			(layer "B.SilkS")
			(effects
				(font
					(size 0.635 0.4064)
					(thickness 0.1524)
				)
				(justify mirror)
			)
		)
		(property "Value" "VAL*"
			(at 0 3.718306 0)
			(unlocked yes)
			(layer "B.Fab")
			(hide yes)
			(effects
				(font
					(size 0.7874 0.5842)
					(thickness 0.127)
				)
				(justify mirror)
			)
		)
		(property "Device Type" "RESISTOR-G155-11000-01,100OHM,A"
			(at 0 1.432306 0)
			(unlocked yes)
			(layer "B.Fab")
			(hide yes)
			(effects
				(font
					(size 0.7874 0.5842)
					(thickness 0.127)
				)
				(justify mirror)
			)
		)
		(property "User Part Number" "PARTNUM*"
			(at 0 2.575306 0)
			(unlocked yes)
			(layer "Cmts.User")
			(hide yes)
			(effects
				(font
					(size 0.7874 0.5842)
					(thickness 0.127)
				)
				(justify mirror)
			)
		)
		(property "Tolerance" "TOL*"
			(at 0 4.861306 0)
			(unlocked yes)
			(layer "Cmts.User")
			(hide yes)
			(effects
				(font
					(size 0.7874 0.5842)
					(thickness 0.127)
				)
				(justify mirror)
			)
		)
		(duplicate_pad_numbers_are_jumpers no)
		(fp_line
			(start -0.970026 -0.4699)
			(end -0.970026 0.4699)
			(stroke
				(width 0.1)
				(type default)
			)
			(layer "B.SilkS")
		)
		(fp_line
			(start -0.970026 0.4699)
			(end 0.970026 0.4699)
			(stroke
				(width 0.1)
				(type default)
			)
			(layer "B.SilkS")
		)
		(fp_line
			(start 0.970026 -0.4699)
			(end -0.970026 -0.4699)
			(stroke
				(width 0.1)
				(type default)
			)
			(layer "B.SilkS")
		)
		(fp_line
			(start 0.970026 0.4699)
			(end 0.970026 -0.4699)
			(stroke
				(width 0.1)
				(type default)
			)
			(layer "B.SilkS")
		)
		(fp_poly
			(pts
				(xy 0.970026 0.4699) (xy -0.970026 0.4699) (xy -0.970026 -0.4699) (xy 0.970026 -0.4699)
			)
			(stroke
				(width 0)
				(type default)
			)
			(fill no)
			(layer "B.CrtYd")
		)
		(fp_line
			(start -0.508 -0.3048)
			(end -0.508 0.3048)
			(stroke
				(width 0.1)
				(type default)
			)
			(layer "B.Fab")
		)
		(fp_line
			(start -0.508 0.3048)
			(end 0.508 0.3048)
			(stroke
				(width 0.1)
				(type default)
			)
			(layer "B.Fab")
		)
		(fp_line
			(start 0.508 -0.3048)
			(end -0.508 -0.3048)
			(stroke
				(width 0.1)
				(type default)
			)
			(layer "B.Fab")
		)
		(fp_line
			(start 0.508 0.3048)
			(end 0.508 -0.3048)
			(stroke
				(width 0.1)
				(type default)
			)
			(layer "B.Fab")
		)
		(pad "1" smd circle
			(at 0.500126 0 180)
			(size 0.635 0.635)
			(layers "B.Cu" "B.Mask" "B.Paste")
			(net "MHZ125CLKP_CLKIN")
		)
		(pad "2" smd circle
			(at -0.500126 0 180)
			(size 0.635 0.635)
			(layers "B.Cu" "B.Mask" "B.Paste")
			(net "MHZ125CLKN_CLKIN")
		)
	)
	(footprint ""
		(layer "B.Cu")
		(at 83.2358 -85.979 180)
		(property "Reference" "R146"
			(at 0.6858 5.54863 0)
			(unlocked yes)
			(layer "B.SilkS")
			(effects
				(font
					(size 0.7874 0.5842)
					(thickness 0.1524)
				)
				(justify mirror)
			)
		)
		(property "Value" "VAL*"
			(at -0.02032 2.13233 180)
			(unlocked yes)
			(layer "B.Fab")
			(hide yes)
			(effects
				(font
					(size 0.7874 0.5842)
					(thickness 0.1524)
				)
				(justify mirror)
			)
		)
		(property "Tolerance" "TOL*"
			(at -0.044704 3.05435 180)
			(unlocked yes)
			(layer "Cmts.User")
			(hide yes)
			(effects
				(font
					(size 0.7874 0.5842)
					(thickness 0.1524)
				)
				(justify mirror)
			)
		)
		(property "User Part Number" "PARTNUM*"
			(at -0.02032 4.024884 180)
			(unlocked yes)
			(layer "Cmts.User")
			(hide yes)
			(effects
				(font
					(size 0.7874 0.5842)
					(thickness 0.1524)
				)
				(justify mirror)
			)
		)
		(property "Device Type" "RESISTOR-G155-11002-01,10KOHM,A"
			(at -0.008382 1.210564 180)
			(unlocked yes)
			(layer "B.Fab")
			(hide yes)
			(effects
				(font
					(size 0.7874 0.5842)
					(thickness 0.1524)
				)
				(justify mirror)
			)
		)
		(duplicate_pad_numbers_are_jumpers no)
		(fp_line
			(start 1.143 0.5588)
			(end -1.143 0.5588)
			(stroke
				(width 0.1)
				(type default)
			)
			(layer "B.SilkS")
		)
		(fp_line
			(start 1.143 -0.5588)
			(end 1.143 0.5588)
			(stroke
				(width 0.1)
				(type default)
			)
			(layer "B.SilkS")
		)
		(fp_line
			(start -1.143 0.5588)
			(end -1.143 -0.5588)
			(stroke
				(width 0.1)
				(type default)
			)
			(layer "B.SilkS")
		)
		(fp_line
			(start -1.143 -0.5588)
			(end 1.143 -0.5588)
			(stroke
				(width 0.1)
				(type default)
			)
			(layer "B.SilkS")
		)
		(fp_rect
			(start -1.143 0.5588)
			(end 1.143 -0.5588)
			(stroke
				(width 0)
				(type default)
			)
			(fill no)
			(layer "B.CrtYd")
		)
		(fp_line
			(start 0.508 0.3048)
			(end -0.508 0.3048)
			(stroke
				(width 0.1)
				(type default)
			)
			(layer "B.Fab")
		)
		(fp_line
			(start 0.508 -0.3048)
			(end 0.508 0.3048)
			(stroke
				(width 0.1)
				(type default)
			)
			(layer "B.Fab")
		)
		(fp_line
			(start -0.508 0.3048)
			(end -0.508 -0.3048)
			(stroke
				(width 0.1)
				(type default)
			)
			(layer "B.Fab")
		)
		(fp_line
			(start -0.508 -0.3048)
			(end 0.508 -0.3048)
			(stroke
				(width 0.1)
				(type default)
			)
			(layer "B.Fab")
		)
		(pad "1" smd rect
			(at 0.5334 0)
			(size 0.7112 0.6096)
			(layers "B.Cu" "B.Mask" "B.Paste")
			(net "XP3R3V_FPGA")
		)
		(pad "2" smd rect
			(at -0.5334 0)
			(size 0.7112 0.6096)
			(layers "B.Cu" "B.Mask" "B.Paste")
			(net "PCA9546_RST_N")
		)
		(zone
			(layer "B.Cu")
			(hatch none 0.5)
			(connect_pads
				(clearance 0)
			)
			(min_thickness 0.25)
			(keepout
				(tracks allowed)
				(vias not_allowed)
				(pads allowed)
				(copperpour not_allowed)
				(footprints allowed)
			)
			(placement
				(enabled no)
				(sheetname "")
			)
			(fill
				(thermal_gap 0.5)
				(thermal_bridge_width 0.5)
				(island_removal_mode 0)
			)
			(polygon
				(pts
					(xy 83.312 -86.2838) (xy 83.1596 -86.2838) (xy 83.1596 -85.6742) (xy 83.312 -85.6742)
				)
			)
		)
	)
)
